(kicad_pcb
	(version 20260206)
	(generator "pcbnew")
	(generator_version "10.0")
	(general
		(thickness 1.6)
		(legacy_teardrops no)
	)
	(paper "A4")
	(title_block
		(title "Bryce Canyon_R.DPB_16317-1_OCP.brd")
		(comment 1 "Bryce Canyon / footprints 880-886 of 2099")
	)
	(layers
		(0 "F.Cu" signal "TOP")
		(4 "In1.Cu" signal "L2GND")
		(6 "In2.Cu" signal "L3")
		(8 "In3.Cu" signal "L4VCC")
		(10 "In4.Cu" signal "L5VCC")
		(12 "In5.Cu" signal "L6")
		(14 "In6.Cu" signal "L7GND")
		(2 "B.Cu" signal "BOTTOM")
		(9 "F.Adhes" user "F.Adhesive")
		(11 "B.Adhes" user "B.Adhesive")
		(13 "F.Paste" user "Package Geometry/Pastemask Top")
		(15 "B.Paste" user "Package Geometry/Pastemask Bottom")
		(5 "F.SilkS" user "Ref Des/Silkscreen Top")
		(7 "B.SilkS" user "Ref Des/Silkscreen Bottom")
		(1 "F.Mask" user "Board Geometry/Soldermask Top")
		(3 "B.Mask" user "Board Geometry/Soldermask Bottom")
		(17 "Dwgs.User" user "User.Drawings")
		(19 "Cmts.User" user "User.Comments")
		(21 "Eco1.User" user "User.Eco1")
		(23 "Eco2.User" user "User.Eco2")
		(25 "Edge.Cuts" user "Board Geometry/Outline")
		(27 "Margin" user)
		(31 "F.CrtYd" user "Package Geometry/Place Bound Top")
		(29 "B.CrtYd" user "Package Geometry/Place Bound Bottom")
		(35 "F.Fab" user "Ref Des/Assembly Top")
		(33 "B.Fab" user "Ref Des/Assembly Bottom")
	)
	(footprint ""
		(layer "F.Cu")
		(at 16.764 -139.065 -90)
		(property "Reference" "C194"
			(at 0 0 270)
			(layer "F.SilkS")
			(hide yes)
			(effects
				(font
					(size 1.27 1.27)
				)
			)
		)
		(property "Value" "SCD033U25V2KX-GP"
			(at 1.1811 -2.7051 270)
			(unlocked yes)
			(layer "F.Fab")
			(hide yes)
			(effects
				(font
					(size 1.016 1.016)
					(thickness 0.1524)
				)
			)
		)
		(property "Device Type" "C402H22"
			(at 1.1811 -4.2291 270)
			(unlocked yes)
			(layer "F.Fab")
			(hide yes)
			(effects
				(font
					(size 1.016 1.016)
					(thickness 0.1524)
				)
			)
		)
		(duplicate_pad_numbers_are_jumpers no)
		(fp_rect
			(start -0.4318 0.9525)
			(end 0.4318 -0.9525)
			(stroke
				(width 0)
				(type default)
			)
			(fill no)
			(layer "F.CrtYd")
		)
		(fp_rect
			(start -0.4318 0.9525)
			(end 0.4318 -0.9525)
			(stroke
				(width 0)
				(type default)
			)
			(fill no)
			(layer "F.Fab")
		)
		(pad "1" smd custom
			(at 0 -0.4445 270)
			(size 0.1524 0.1524)
			(layers "F.Cu" "F.Mask" "F.Paste")
			(net "SW_HDD_P12")
			(options
				(clearance outline)
				(anchor circle)
			)
			(primitives
				(gr_poly
					(pts
						(arc
							(start 0.3048 -0.2032)
							(mid 0.275042 -0.275042)
							(end 0.2032 -0.3048)
						)
						(arc
							(start -0.2032 -0.3048)
							(mid -0.275042 -0.275042)
							(end -0.3048 -0.2032)
						)
						(arc
							(start -0.3048 0.2032)
							(mid -0.275042 0.275042)
							(end -0.2032 0.3048)
						)
						(arc
							(start 0.2032 0.3048)
							(mid 0.275042 0.275042)
							(end 0.3048 0.2032)
						)
					)
					(width 0)
					(fill yes)
				)
			)
		)
		(pad "2" smd custom
			(at 0 0.4445 270)
			(size 0.1524 0.1524)
			(layers "F.Cu" "F.Mask" "F.Paste")
			(net "GND")
			(options
				(clearance outline)
				(anchor circle)
			)
			(primitives
				(gr_poly
					(pts
						(arc
							(start 0.3048 -0.2032)
							(mid 0.275042 -0.275042)
							(end 0.2032 -0.3048)
						)
						(arc
							(start -0.2032 -0.3048)
							(mid -0.275042 -0.275042)
							(end -0.3048 -0.2032)
						)
						(arc
							(start -0.3048 0.2032)
							(mid -0.275042 0.275042)
							(end -0.2032 0.3048)
						)
						(arc
							(start 0.2032 0.3048)
							(mid 0.275042 0.275042)
							(end 0.3048 0.2032)
						)
					)
					(width 0)
					(fill yes)
				)
			)
		)
	)
	(footprint ""
		(layer "F.Cu")
		(at 50.82286 -120.977406)
		(property "Reference" "R1116"
			(at 0 0 0)
			(layer "F.SilkS")
			(hide yes)
			(effects
				(font
					(size 1.27 1.27)
				)
			)
		)
		(property "Value" "49K9R2F-L-GP"
			(at 0.064008 -3.993896 0)
			(unlocked yes)
			(layer "F.Fab")
			(hide yes)
			(effects
				(font
					(size 1.016 1.016)
					(thickness 0.1524)
				)
			)
		)
		(property "Device Type" "R402H16"
			(at 0.064008 -5.517896 0)
			(unlocked yes)
			(layer "F.Fab")
			(hide yes)
			(effects
				(font
					(size 1.016 1.016)
					(thickness 0.1524)
				)
			)
		)
		(duplicate_pad_numbers_are_jumpers no)
		(fp_line
			(start -0.508 -0.9398)
			(end -0.508 0.9398)
			(stroke
				(width 0.1524)
				(type default)
			)
			(layer "F.SilkS")
		)
		(fp_line
			(start 0.508 -0.9398)
			(end -0.508 -0.9398)
			(stroke
				(width 0.1524)
				(type default)
			)
			(layer "F.SilkS")
		)
		(fp_rect
			(start -0.508 0.9398)
			(end 0.508 -0.9398)
			(stroke
				(width 0)
				(type default)
			)
			(fill no)
			(layer "F.CrtYd")
		)
		(fp_rect
			(start -0.508 0.9398)
			(end 0.508 -0.9398)
			(stroke
				(width 0)
				(type default)
			)
			(fill no)
			(layer "F.Fab")
		)
		(pad "1" smd custom
			(at 0 -0.4445)
			(size 0.1397 0.1397)
			(layers "F.Cu" "F.Mask" "F.Paste")
			(net "P12V_B")
			(options
				(clearance outline)
				(anchor circle)
			)
			(primitives
				(gr_poly
					(pts
						(arc
							(start -0.1778 -0.2794)
							(mid -0.249642 -0.249642)
							(end -0.2794 -0.1778)
						)
						(arc
							(start -0.2794 0.1778)
							(mid -0.249642 0.249642)
							(end -0.1778 0.2794)
						)
						(arc
							(start 0.1778 0.2794)
							(mid 0.249642 0.249642)
							(end 0.2794 0.1778)
						)
						(arc
							(start 0.2794 -0.1778)
							(mid 0.249642 -0.249642)
							(end 0.1778 -0.2794)
						)
					)
					(width 0)
					(fill yes)
				)
			)
		)
		(pad "2" smd custom
			(at 0 0.4445)
			(size 0.1397 0.1397)
			(layers "F.Cu" "F.Mask" "F.Paste")
			(net "P5V_B_2_EN_R")
			(options
				(clearance outline)
				(anchor circle)
			)
			(primitives
				(gr_poly
					(pts
						(arc
							(start -0.1778 -0.2794)
							(mid -0.249642 -0.249642)
							(end -0.2794 -0.1778)
						)
						(arc
							(start -0.2794 0.1778)
							(mid -0.249642 0.249642)
							(end -0.1778 0.2794)
						)
						(arc
							(start 0.1778 0.2794)
							(mid 0.249642 0.249642)
							(end 0.2794 0.1778)
						)
						(arc
							(start 0.2794 -0.1778)
							(mid 0.249642 -0.249642)
							(end 0.1778 -0.2794)
						)
					)
					(width 0)
					(fill yes)
				)
			)
		)
	)
	(footprint ""
		(layer "F.Cu")
		(at 176.657 -35.687 90)
		(property "Reference" "R738"
			(at 0 0 90)
			(layer "F.SilkS")
			(hide yes)
			(effects
				(font
					(size 1.27 1.27)
				)
			)
		)
		(property "Value" "2R6F-GP"
			(at -0.0508 -4.8514 90)
			(unlocked yes)
			(layer "F.Fab")
			(hide yes)
			(effects
				(font
					(size 1.016 1.016)
					(thickness 0.1524)
				)
			)
		)
		(property "Device Type" "R1206H26"
			(at 0 -6.3754 90)
			(unlocked yes)
			(layer "F.Fab")
			(hide yes)
			(effects
				(font
					(size 1.016 1.016)
					(thickness 0.1524)
				)
			)
		)
		(duplicate_pad_numbers_are_jumpers no)
		(fp_line
			(start 1.016 -2.2352)
			(end 1.016 2.2352)
			(stroke
				(width 0.1524)
				(type default)
			)
			(layer "F.SilkS")
		)
		(fp_line
			(start -1.016 -2.2352)
			(end 1.016 -2.2352)
			(stroke
				(width 0.1524)
				(type default)
			)
			(layer "F.SilkS")
		)
		(fp_line
			(start 1.016 2.2352)
			(end -1.016 2.2352)
			(stroke
				(width 0.1524)
				(type default)
			)
			(layer "F.SilkS")
		)
		(fp_line
			(start -1.016 2.2352)
			(end -1.016 -2.2352)
			(stroke
				(width 0.1524)
				(type default)
			)
			(layer "F.SilkS")
		)
		(fp_rect
			(start -1.0922 2.3114)
			(end 1.0922 -2.3114)
			(stroke
				(width 0)
				(type default)
			)
			(fill no)
			(layer "F.CrtYd")
		)
		(fp_poly
			(pts
				(xy -1.0922 -2.3114) (xy 1.0922 -2.3114) (xy 1.0922 2.3114) (xy -1.0922 2.3114)
			)
			(stroke
				(width 0)
				(type default)
			)
			(fill no)
			(layer "F.Fab")
		)
		(pad "1" smd rect
			(at 0 -1.397 90)
			(size 1.651 1.27)
			(layers "F.Cu" "F.Mask" "F.Paste")
			(net "P12V_HDD29")
		)
		(pad "2" smd rect
			(at 0 1.397 90)
			(size 1.651 1.27)
			(layers "F.Cu" "F.Mask" "F.Paste")
			(net "12V_PRE_29")
		)
	)
	(footprint ""
		(layer "F.Cu")
		(at 446.9384 -31.6484 180)
		(property "Reference" "R852"
			(at 0 0 180)
			(layer "F.SilkS")
			(hide yes)
			(effects
				(font
					(size 1.27 1.27)
				)
			)
		)
		(property "Value" "10KR2F-2-GP"
			(at 0.064008 -3.993896 180)
			(unlocked yes)
			(layer "F.Fab")
			(hide yes)
			(effects
				(font
					(size 1.016 1.016)
					(thickness 0.1524)
				)
			)
		)
		(property "Device Type" "R402H16"
			(at 0.064008 -5.517896 180)
			(unlocked yes)
			(layer "F.Fab")
			(hide yes)
			(effects
				(font
					(size 1.016 1.016)
					(thickness 0.1524)
				)
			)
		)
		(duplicate_pad_numbers_are_jumpers no)
		(fp_line
			(start 0.508 -0.9398)
			(end -0.508 -0.9398)
			(stroke
				(width 0.1524)
				(type default)
			)
			(layer "F.SilkS")
		)
		(fp_line
			(start -0.508 -0.9398)
			(end -0.508 0.9398)
			(stroke
				(width 0.1524)
				(type default)
			)
			(layer "F.SilkS")
		)
		(fp_rect
			(start -0.508 0.9398)
			(end 0.508 -0.9398)
			(stroke
				(width 0)
				(type default)
			)
			(fill no)
			(layer "F.CrtYd")
		)
		(fp_rect
			(start -0.508 0.9398)
			(end 0.508 -0.9398)
			(stroke
				(width 0)
				(type default)
			)
			(fill no)
			(layer "F.Fab")
		)
		(pad "1" smd custom
			(at 0 -0.4445 180)
			(size 0.1397 0.1397)
			(layers "F.Cu" "F.Mask" "F.Paste")
			(net "P3V3_STBY_B")
			(options
				(clearance outline)
				(anchor circle)
			)
			(primitives
				(gr_poly
					(pts
						(arc
							(start -0.1778 -0.2794)
							(mid -0.249642 -0.249642)
							(end -0.2794 -0.1778)
						)
						(arc
							(start -0.2794 0.1778)
							(mid -0.249642 0.249642)
							(end -0.1778 0.2794)
						)
						(arc
							(start 0.1778 0.2794)
							(mid 0.249642 0.249642)
							(end 0.2794 0.1778)
						)
						(arc
							(start 0.2794 -0.1778)
							(mid 0.249642 -0.249642)
							(end 0.1778 -0.2794)
						)
					)
					(width 0)
					(fill yes)
				)
			)
		)
		(pad "2" smd custom
			(at 0 0.4445 180)
			(size 0.1397 0.1397)
			(layers "F.Cu" "F.Mask" "F.Paste")
			(net "HDD_PRSNT_34")
			(options
				(clearance outline)
				(anchor circle)
			)
			(primitives
				(gr_poly
					(pts
						(arc
							(start -0.1778 -0.2794)
							(mid -0.249642 -0.249642)
							(end -0.2794 -0.1778)
						)
						(arc
							(start -0.2794 0.1778)
							(mid -0.249642 0.249642)
							(end -0.1778 0.2794)
						)
						(arc
							(start 0.1778 0.2794)
							(mid 0.249642 0.249642)
							(end 0.2794 0.1778)
						)
						(arc
							(start 0.2794 -0.1778)
							(mid 0.249642 -0.249642)
							(end 0.1778 -0.2794)
						)
					)
					(width 0)
					(fill yes)
				)
			)
		)
	)
	(footprint ""
		(layer "F.Cu")
		(at 332.105 -246.253 -90)
		(property "Reference" "Q23"
			(at 0 0 270)
			(layer "F.SilkS")
			(hide yes)
			(effects
				(font
					(size 1.27 1.27)
				)
			)
		)
		(property "Value" "2N7002KDW-GP"
			(at -2.3622 -8.2042 270)
			(unlocked yes)
			(layer "F.Fab")
			(hide yes)
			(effects
				(font
					(size 1.016 1.016)
					(thickness 0.1524)
				)
			)
		)
		(property "Device Type" "SOT-363H44"
			(at -2.3622 -10.1092 270)
			(unlocked yes)
			(layer "F.Fab")
			(hide yes)
			(effects
				(font
					(size 1.016 1.016)
					(thickness 0.1524)
				)
			)
		)
		(duplicate_pad_numbers_are_jumpers no)
		(fp_line
			(start -1.4478 1.7018)
			(end 1.4478 1.7018)
			(stroke
				(width 0.1524)
				(type default)
			)
			(layer "F.SilkS")
		)
		(fp_line
			(start 1.4478 1.7018)
			(end 1.4478 -1.7018)
			(stroke
				(width 0.1524)
				(type default)
			)
			(layer "F.SilkS")
		)
		(fp_line
			(start -1.27 1.524)
			(end -1.27 0.6604)
			(stroke
				(width 0.4826)
				(type default)
			)
			(layer "F.SilkS")
		)
		(fp_line
			(start -1.4478 -1.7018)
			(end -1.4478 1.7018)
			(stroke
				(width 0.1524)
				(type default)
			)
			(layer "F.SilkS")
		)
		(fp_line
			(start 1.4478 -1.7018)
			(end -1.4478 -1.7018)
			(stroke
				(width 0.1524)
				(type default)
			)
			(layer "F.SilkS")
		)
		(fp_poly
			(pts
				(xy -1.524 -1.778) (xy 1.524 -1.778) (xy 1.524 1.778) (xy -1.524 1.778)
			)
			(stroke
				(width 0)
				(type default)
			)
			(fill no)
			(layer "F.CrtYd")
		)
		(fp_poly
			(pts
				(xy -1.524 -1.778) (xy 1.524 -1.778) (xy 1.524 1.778) (xy -1.524 1.778)
			)
			(stroke
				(width 0)
				(type default)
			)
			(fill no)
			(layer "F.Fab")
		)
		(pad "1" smd rect
			(at -0.65024 0.9398 270)
			(size 0.4064 1.016)
			(layers "F.Cu" "F.Mask" "F.Paste")
			(net "GND")
		)
		(pad "2" smd rect
			(at 0 0.9398 270)
			(size 0.4064 1.016)
			(layers "F.Cu" "F.Mask" "F.Paste")
			(net "SW_PWR_R_HDD6")
		)
		(pad "3" smd rect
			(at 0.65024 0.9398 270)
			(size 0.4064 1.016)
			(layers "F.Cu" "F.Mask" "F.Paste")
			(net "SW_HDD_P6")
		)
		(pad "4" smd rect
			(at 0.65024 -0.9398 270)
			(size 0.4064 1.016)
			(layers "F.Cu" "F.Mask" "F.Paste")
			(net "GND")
		)
		(pad "5" smd rect
			(at 0 -0.9398 270)
			(size 0.4064 1.016)
			(layers "F.Cu" "F.Mask" "F.Paste")
			(net "SW_HDD_G6")
		)
		(pad "6" smd rect
			(at -0.65024 -0.9398 270)
			(size 0.4064 1.016)
			(layers "F.Cu" "F.Mask" "F.Paste")
			(net "SW_HDD_R6")
		)
	)
	(footprint ""
		(layer "F.Cu")
		(at 77.978 -246.634 90)
		(property "Reference" "R200"
			(at 0 0 90)
			(layer "F.SilkS")
			(hide yes)
			(effects
				(font
					(size 1.27 1.27)
				)
			)
		)
		(property "Value" "4K7R2J-2-GP"
			(at 0.064008 -3.993896 90)
			(unlocked yes)
			(layer "F.Fab")
			(hide yes)
			(effects
				(font
					(size 1.016 1.016)
					(thickness 0.1524)
				)
			)
		)
		(property "Device Type" "R402H16"
			(at 0.064008 -5.517896 90)
			(unlocked yes)
			(layer "F.Fab")
			(hide yes)
			(effects
				(font
					(size 1.016 1.016)
					(thickness 0.1524)
				)
			)
		)
		(duplicate_pad_numbers_are_jumpers no)
		(fp_line
			(start 0.508 -0.9398)
			(end -0.508 -0.9398)
			(stroke
				(width 0.1524)
				(type default)
			)
			(layer "F.SilkS")
		)
		(fp_line
			(start -0.508 -0.9398)
			(end -0.508 0.9398)
			(stroke
				(width 0.1524)
				(type default)
			)
			(layer "F.SilkS")
		)
		(fp_rect
			(start -0.508 0.9398)
			(end 0.508 -0.9398)
			(stroke
				(width 0)
				(type default)
			)
			(fill no)
			(layer "F.CrtYd")
		)
		(fp_rect
			(start -0.508 0.9398)
			(end 0.508 -0.9398)
			(stroke
				(width 0)
				(type default)
			)
			(fill no)
			(layer "F.Fab")
		)
		(pad "1" smd custom
			(at 0 -0.4445 90)
			(size 0.1397 0.1397)
			(layers "F.Cu" "F.Mask" "F.Paste")
			(net "P12V_B")
			(options
				(clearance outline)
				(anchor circle)
			)
			(primitives
				(gr_poly
					(pts
						(arc
							(start -0.1778 -0.2794)
							(mid -0.249642 -0.249642)
							(end -0.2794 -0.1778)
						)
						(arc
							(start -0.2794 0.1778)
							(mid -0.249642 0.249642)
							(end -0.1778 0.2794)
						)
						(arc
							(start 0.1778 0.2794)
							(mid 0.249642 0.249642)
							(end 0.2794 0.1778)
						)
						(arc
							(start 0.2794 -0.1778)
							(mid 0.249642 -0.249642)
							(end 0.1778 -0.2794)
						)
					)
					(width 0)
					(fill yes)
				)
			)
		)
		(pad "2" smd custom
			(at 0 0.4445 90)
			(size 0.1397 0.1397)
			(layers "F.Cu" "F.Mask" "F.Paste")
			(net "SW_HDD_R2")
			(options
				(clearance outline)
				(anchor circle)
			)
			(primitives
				(gr_poly
					(pts
						(arc
							(start -0.1778 -0.2794)
							(mid -0.249642 -0.249642)
							(end -0.2794 -0.1778)
						)
						(arc
							(start -0.2794 0.1778)
							(mid -0.249642 0.249642)
							(end -0.1778 0.2794)
						)
						(arc
							(start 0.1778 0.2794)
							(mid 0.249642 0.249642)
							(end 0.2794 0.1778)
						)
						(arc
							(start 0.2794 -0.1778)
							(mid 0.249642 -0.249642)
							(end 0.1778 -0.2794)
						)
					)
					(width 0)
					(fill yes)
				)
			)
		)
	)
	(footprint ""
		(layer "F.Cu")
		(at 429.514 -253.873 -90)
		(property "Reference" "Q34"
			(at 0 0 270)
			(layer "F.SilkS")
			(hide yes)
			(effects
				(font
					(size 1.27 1.27)
				)
			)
		)
		(property "Value" "AO4406AL-GP"
			(at -3.707384 -1.5367 270)
			(unlocked yes)
			(layer "F.Fab")
			(hide yes)
			(effects
				(font
					(size 1.016 1.016)
					(thickness 0.1524)
				)
			)
		)
		(property "Device Type" "SOIC8H69"
			(at -3.707384 -3.0607 270)
			(unlocked yes)
			(layer "F.Fab")
			(hide yes)
			(effects
				(font
					(size 1.016 1.016)
					(thickness 0.1524)
				)
			)
		)
		(duplicate_pad_numbers_are_jumpers no)
		(fp_line
			(start -2.6289 3.4417)
			(end -2.6289 1.4732)
			(stroke
				(width 0.381)
				(type default)
			)
			(layer "F.SilkS")
		)
		(fp_line
			(start -2.7432 1.4224)
			(end -2.6416 1.4224)
			(stroke
				(width 0.1524)
				(type default)
			)
			(layer "F.SilkS")
		)
		(fp_line
			(start -2.7432 1.4224)
			(end 2.1336 1.4224)
			(stroke
				(width 0.1524)
				(type default)
			)
			(layer "F.SilkS")
		)
		(fp_line
			(start 2.1336 1.4224)
			(end 2.1336 -1.4224)
			(stroke
				(width 0.1524)
				(type default)
			)
			(layer "F.SilkS")
		)
		(fp_line
			(start -2.1844 -0.0508)
			(end -2.7178 0.508)
			(stroke
				(width 0.1524)
				(type default)
			)
			(layer "F.SilkS")
		)
		(fp_line
			(start -2.7178 -0.508)
			(end -2.1844 -0.0508)
			(stroke
				(width 0.1524)
				(type default)
			)
			(layer "F.SilkS")
		)
		(fp_line
			(start -2.7432 -1.4224)
			(end -2.7432 1.4224)
			(stroke
				(width 0.1524)
				(type default)
			)
			(layer "F.SilkS")
		)
		(fp_line
			(start 2.1336 -1.4224)
			(end -2.7432 -1.4224)
			(stroke
				(width 0.1524)
				(type default)
			)
			(layer "F.SilkS")
		)
		(fp_poly
			(pts
				(xy -2.2098 -1.4224) (xy -2.2098 1.4224) (xy 2.2098 1.4224) (xy 2.2098 -1.4224)
			)
			(stroke
				(width 0)
				(type default)
			)
			(fill yes)
			(layer "F.SilkS")
		)
		(fp_rect
			(start -2.450084 2.999994)
			(end 2.450084 -2.999994)
			(stroke
				(width 0)
				(type default)
			)
			(fill no)
			(layer "F.CrtYd")
		)
		(fp_poly
			(pts
				(xy -2.8194 3.6322) (xy -2.8194 -3.6322) (xy 2.8194 -3.6322) (xy 2.8194 1.18364) (xy 2.450084 1.18364)
				(xy 2.450084 -2.999994) (xy -2.450084 -2.999994) (xy -2.450084 2.999994) (xy 2.450084 2.999994)
				(xy 2.450084 1.18618) (xy 2.8194 1.18618) (xy 2.8194 3.6322)
			)
			(stroke
				(width 0)
				(type default)
			)
			(fill no)
			(layer "F.CrtYd")
		)
		(fp_rect
			(start -2.8194 3.6322)
			(end 2.8194 -3.6322)
			(stroke
				(width 0)
				(type default)
			)
			(fill no)
			(layer "F.Fab")
		)
		(pad "1" smd rect
			(at -1.905 2.54 270)
			(size 0.635 1.651)
			(layers "F.Cu" "F.Mask" "F.Paste")
			(net "P5V_HDD9")
		)
		(pad "2" smd rect
			(at -0.635 2.54 270)
			(size 0.635 1.651)
			(layers "F.Cu" "F.Mask" "F.Paste")
			(net "P5V_HDD9")
		)
		(pad "3" smd rect
			(at 0.635 2.54 270)
			(size 0.635 1.651)
			(layers "F.Cu" "F.Mask" "F.Paste")
			(net "P5V_HDD9")
		)
		(pad "4" smd rect
			(at 1.905 2.54 270)
			(size 0.635 1.651)
			(layers "F.Cu" "F.Mask" "F.Paste")
			(net "SW_HDD_P9")
		)
		(pad "5" smd rect
			(at 1.905 -2.54 270)
			(size 0.635 1.651)
			(layers "F.Cu" "F.Mask" "F.Paste")
			(net "P5V_B_3")
		)
		(pad "6" smd rect
			(at 0.635 -2.54 270)
			(size 0.635 1.651)
			(layers "F.Cu" "F.Mask" "F.Paste")
			(net "P5V_B_3")
		)
		(pad "7" smd rect
			(at -0.635 -2.54 270)
			(size 0.635 1.651)
			(layers "F.Cu" "F.Mask" "F.Paste")
			(net "P5V_B_3")
		)
		(pad "8" smd rect
			(at -1.905 -2.54 270)
			(size 0.635 1.651)
			(layers "F.Cu" "F.Mask" "F.Paste")
			(net "P5V_B_3")
		)
	)
)
